(kicad_pcb
	(version 20260206)
	(generator "pcbnew")
	(generator_version "10.0")
	(general
		(thickness 1.6)
		(legacy_teardrops no)
	)
	(paper "A4")
	(title_block
		(title "pdpb — Lightning_PDPB_BRD.brd")
		(comment 1 "Lightning (Wiwynn / Facebook NVMe JBOF) / footprints 258-263 of 1140")
	)
	(layers
		(0 "F.Cu" signal "TOP")
		(4 "In1.Cu" signal "L2GND")
		(6 "In2.Cu" signal "L3")
		(8 "In3.Cu" signal "L4VCC")
		(10 "In4.Cu" signal "L5VCC")
		(12 "In5.Cu" signal "L6")
		(14 "In6.Cu" signal "L7GND")
		(2 "B.Cu" signal "BOTTOM")
		(9 "F.Adhes" user "F.Adhesive")
		(11 "B.Adhes" user "B.Adhesive")
		(13 "F.Paste" user "Package Geometry/Pastemask Top")
		(15 "B.Paste" user "Package Geometry/Pastemask Bottom")
		(5 "F.SilkS" user "Ref Des/Silkscreen Top")
		(7 "B.SilkS" user "Ref Des/Silkscreen Bottom")
		(1 "F.Mask" user "Board Geometry/Soldermask Top")
		(3 "B.Mask" user "Board Geometry/Soldermask Bottom")
		(17 "Dwgs.User" user "User.Drawings")
		(19 "Cmts.User" user "User.Comments")
		(21 "Eco1.User" user "User.Eco1")
		(23 "Eco2.User" user "User.Eco2")
		(25 "Edge.Cuts" user "Board Geometry/Outline")
		(27 "Margin" user)
		(31 "F.CrtYd" user "Package Geometry/Place Bound Top")
		(29 "B.CrtYd" user "Package Geometry/Place Bound Bottom")
		(35 "F.Fab" user "Ref Des/Assembly Top")
		(33 "B.Fab" user "Ref Des/Assembly Bottom")
	)
	(footprint ""
		(layer "F.Cu")
		(at 37.973 -411.734 180)
		(property "Reference" "R9770"
			(at 0 0 180)
			(layer "F.SilkS")
			(hide yes)
			(effects
				(font
					(size 1.27 1.27)
				)
			)
		)
		(property "Value" "4K7R2J-2-GP"
			(at 0.064008 -3.993896 180)
			(unlocked yes)
			(layer "F.Fab")
			(hide yes)
			(effects
				(font
					(size 1.016 1.016)
					(thickness 0.1524)
				)
			)
		)
		(property "Device Type" "R402H16"
			(at 0.064008 -5.517896 180)
			(unlocked yes)
			(layer "F.Fab")
			(hide yes)
			(effects
				(font
					(size 1.016 1.016)
					(thickness 0.1524)
				)
			)
		)
		(duplicate_pad_numbers_are_jumpers no)
		(fp_line
			(start 0.508 -0.9398)
			(end -0.508 -0.9398)
			(stroke
				(width 0.1524)
				(type default)
			)
			(layer "F.SilkS")
		)
		(fp_line
			(start -0.508 -0.9398)
			(end -0.508 0.9398)
			(stroke
				(width 0.1524)
				(type default)
			)
			(layer "F.SilkS")
		)
		(fp_rect
			(start -0.508 0.9398)
			(end 0.508 -0.9398)
			(stroke
				(width 0)
				(type default)
			)
			(fill no)
			(layer "F.CrtYd")
		)
		(fp_rect
			(start -0.508 0.9398)
			(end 0.508 -0.9398)
			(stroke
				(width 0)
				(type default)
			)
			(fill no)
			(layer "F.Fab")
		)
		(pad "1" smd custom
			(at 0 -0.4445 180)
			(size 0.1397 0.1397)
			(layers "F.Cu" "F.Mask" "F.Paste")
			(net "SSD10_PWREN")
			(options
				(clearance outline)
				(anchor circle)
			)
			(primitives
				(gr_poly
					(pts
						(arc
							(start -0.1778 -0.2794)
							(mid -0.249642 -0.249642)
							(end -0.2794 -0.1778)
						)
						(arc
							(start -0.2794 0.1778)
							(mid -0.249642 0.249642)
							(end -0.1778 0.2794)
						)
						(arc
							(start 0.1778 0.2794)
							(mid 0.249642 0.249642)
							(end 0.2794 0.1778)
						)
						(arc
							(start 0.2794 -0.1778)
							(mid 0.249642 -0.249642)
							(end 0.1778 -0.2794)
						)
					)
					(width 0)
					(fill yes)
				)
			)
		)
		(pad "2" smd custom
			(at 0 0.4445 180)
			(size 0.1397 0.1397)
			(layers "F.Cu" "F.Mask" "F.Paste")
			(net "GND")
			(options
				(clearance outline)
				(anchor circle)
			)
			(primitives
				(gr_poly
					(pts
						(arc
							(start -0.1778 -0.2794)
							(mid -0.249642 -0.249642)
							(end -0.2794 -0.1778)
						)
						(arc
							(start -0.2794 0.1778)
							(mid -0.249642 0.249642)
							(end -0.1778 0.2794)
						)
						(arc
							(start 0.1778 0.2794)
							(mid 0.249642 0.249642)
							(end 0.2794 0.1778)
						)
						(arc
							(start 0.2794 -0.1778)
							(mid 0.249642 -0.249642)
							(end 0.1778 -0.2794)
						)
					)
					(width 0)
					(fill yes)
				)
			)
		)
	)
	(footprint ""
		(layer "F.Cu")
		(at 253.499874 -174.497492)
		(property "Reference" "H8"
			(at 0 0 0)
			(layer "F.SilkS")
			(hide yes)
			(effects
				(font
					(size 1.27 1.27)
				)
			)
		)
		(property "Value" "GEN276X162R197X296-6-F-A-GP"
			(at -6.7183 4.1402 0)
			(unlocked yes)
			(layer "F.Fab")
			(hide yes)
			(effects
				(font
					(size 1.016 1.016)
					(thickness 0.1524)
				)
			)
		)
		(property "Device Type" "GEN276X162R197X296-6-F-A"
			(at -6.7183 2.6162 0)
			(unlocked yes)
			(layer "F.Fab")
			(hide yes)
			(effects
				(font
					(size 1.016 1.016)
					(thickness 0.1524)
				)
			)
		)
		(duplicate_pad_numbers_are_jumpers no)
		(fp_poly
			(pts
				(arc
					(start 2.723642 4.777232)
					(mid -0.000169 6.508462)
					(end -2.723896 4.776978)
				)
				(arc
					(start -2.723896 4.776978)
					(mid 0.000173 -5.499012)
					(end 2.723642 4.777232)
				)
			)
			(stroke
				(width 0)
				(type default)
			)
			(fill no)
			(layer "B.CrtYd")
		)
		(fp_poly
			(pts
				(arc
					(start 2.723642 4.777232)
					(mid -0.000169 6.508462)
					(end -2.723896 4.776978)
				)
				(arc
					(start -2.723896 4.776978)
					(mid 0.000173 -5.499012)
					(end 2.723642 4.777232)
				)
			)
			(stroke
				(width 0)
				(type default)
			)
			(fill no)
			(layer "F.CrtYd")
		)
		(fp_poly
			(pts
				(arc
					(start 2.723642 4.777232)
					(mid -0.000169 6.508462)
					(end -2.723896 4.776978)
				)
				(arc
					(start -2.723896 4.776978)
					(mid 0.000173 -5.499012)
					(end 2.723642 4.777232)
				)
			)
			(stroke
				(width 0)
				(type default)
			)
			(fill no)
			(layer "B.Fab")
		)
		(fp_poly
			(pts
				(arc
					(start 2.723642 4.777232)
					(mid -0.000169 6.508462)
					(end -2.723896 4.776978)
				)
				(arc
					(start -2.723896 4.776978)
					(mid 0.000173 -5.499012)
					(end 2.723642 4.777232)
				)
			)
			(stroke
				(width 0)
				(type default)
			)
			(fill no)
			(layer "F.Fab")
		)
		(pad "" np_thru_hole circle
			(at 0 0)
			(size 0.254 0.254)
			(drill 0.0254)
			(layers "*.Cu" "*.Mask")
			(clearance 3.135376)
			(thermal_gap 3.135376)
		)
		(pad "1" thru_hole circle
			(at 2.549906 0)
			(size 0.8636 0.8636)
			(drill 0.508)
			(layers "*.Cu" "*.Mask")
			(remove_unused_layers no)
			(net "GND")
			(clearance 0.8255)
			(thermal_gap 0.8255)
		)
		(pad "2" thru_hole circle
			(at 2.210054 -1.27)
			(size 0.8636 0.8636)
			(drill 0.508)
			(layers "*.Cu" "*.Mask")
			(remove_unused_layers no)
			(net "GND")
			(clearance 0.8255)
			(thermal_gap 0.8255)
		)
		(pad "3" thru_hole circle
			(at 1.27 -2.210054)
			(size 0.8636 0.8636)
			(drill 0.508)
			(layers "*.Cu" "*.Mask")
			(remove_unused_layers no)
			(net "GND")
			(clearance 0.8255)
			(thermal_gap 0.8255)
		)
		(pad "4" thru_hole circle
			(at -1.279906 -2.210054)
			(size 0.8636 0.8636)
			(drill 0.508)
			(layers "*.Cu" "*.Mask")
			(remove_unused_layers no)
			(net "GND")
			(clearance 0.8255)
			(thermal_gap 0.8255)
		)
		(pad "5" thru_hole circle
			(at -2.210054 -1.27)
			(size 0.8636 0.8636)
			(drill 0.508)
			(layers "*.Cu" "*.Mask")
			(remove_unused_layers no)
			(net "GND")
			(clearance 0.8255)
			(thermal_gap 0.8255)
		)
		(pad "6" thru_hole circle
			(at -2.549906 0)
			(size 0.8636 0.8636)
			(drill 0.508)
			(layers "*.Cu" "*.Mask")
			(remove_unused_layers no)
			(net "GND")
			(clearance 0.8255)
			(thermal_gap 0.8255)
		)
		(zone
			(layers "F.Cu" "B.Cu" "In1.Cu" "In2.Cu" "In3.Cu" "In4.Cu" "In5.Cu" "In6.Cu")
			(hatch none 0.5)
			(connect_pads
				(clearance 0)
			)
			(min_thickness 0.25)
			(keepout
				(tracks allowed)
				(vias not_allowed)
				(pads allowed)
				(copperpour not_allowed)
				(footprints allowed)
			)
			(placement
				(enabled no)
				(sheetname "")
			)
			(fill
				(thermal_gap 0.5)
				(thermal_bridge_width 0.5)
				(island_removal_mode 0)
			)
			(polygon
				(pts
					(arc
						(start 257.817874 -174.50054)
						(mid 249.181874 -174.50054)
						(end 257.817874 -174.50054)
					)
				)
			)
		)
		(zone
			(layers "F.Cu" "B.Cu" "In1.Cu" "In2.Cu" "In3.Cu" "In4.Cu" "In5.Cu" "In6.Cu")
			(hatch none 0.5)
			(connect_pads
				(clearance 0)
			)
			(min_thickness 0.25)
			(keepout
				(tracks not_allowed)
				(vias allowed)
				(pads allowed)
				(copperpour not_allowed)
				(footprints allowed)
			)
			(placement
				(enabled no)
				(sheetname "")
			)
			(fill
				(thermal_gap 0.5)
				(thermal_bridge_width 0.5)
				(island_removal_mode 0)
			)
			(polygon
				(pts
					(arc
						(start 255.839214 -172.888148)
						(mid 253.499954 -167.989045)
						(end 251.16028 -172.888148)
					)
					(arc
						(start 251.16028 -172.888148)
						(mid 251.406247 -173.328514)
						(end 251.491496 -173.825662)
					)
					(arc
						(start 251.491496 -174.497492)
						(mid 253.499874 -176.50587)
						(end 255.507998 -174.497492)
					)
					(arc
						(start 255.507998 -173.825662)
						(mid 255.593233 -173.328508)
						(end 255.839214 -172.888148)
					)
				)
			)
		)
	)
	(footprint ""
		(layer "F.Cu")
		(at 200.365106 -495.174778 180)
		(property "Reference" "Q8"
			(at 0 0 180)
			(layer "F.SilkS")
			(hide yes)
			(effects
				(font
					(size 1.27 1.27)
				)
			)
		)
		(property "Value" "2N7002A-7-GP"
			(at 0.127 -8.9662 180)
			(unlocked yes)
			(layer "F.Fab")
			(hide yes)
			(effects
				(font
					(size 1.016 1.016)
					(thickness 0.1524)
				)
			)
		)
		(property "Device Type" "SOT23DGS2D4H48"
			(at 0.127 -10.4902 180)
			(unlocked yes)
			(layer "F.Fab")
			(hide yes)
			(effects
				(font
					(size 1.016 1.016)
					(thickness 0.1524)
				)
			)
		)
		(duplicate_pad_numbers_are_jumpers no)
		(fp_line
			(start 1.651 1.778)
			(end 1.651 -1.778)
			(stroke
				(width 0.1524)
				(type default)
			)
			(layer "F.SilkS")
		)
		(fp_line
			(start 1.651 -1.778)
			(end -1.651 -1.778)
			(stroke
				(width 0.1524)
				(type default)
			)
			(layer "F.SilkS")
		)
		(fp_line
			(start -1.651 1.778)
			(end 1.651 1.778)
			(stroke
				(width 0.1524)
				(type default)
			)
			(layer "F.SilkS")
		)
		(fp_line
			(start -1.651 -1.778)
			(end -1.651 1.778)
			(stroke
				(width 0.1524)
				(type default)
			)
			(layer "F.SilkS")
		)
		(fp_poly
			(pts
				(xy -1.778 1.8796) (xy -1.778 -1.8796) (xy 1.778 -1.8796) (xy 1.778 1.8796)
			)
			(stroke
				(width 0)
				(type default)
			)
			(fill no)
			(layer "F.CrtYd")
		)
		(fp_poly
			(pts
				(xy -1.778 1.8796) (xy -1.778 -1.8796) (xy 1.778 -1.8796) (xy 1.778 1.8796)
			)
			(stroke
				(width 0)
				(type default)
			)
			(fill no)
			(layer "F.Fab")
		)
		(pad "D" smd custom
			(at 0 -0.9525 180)
			(size 0.1905 0.1905)
			(layers "F.Cu" "F.Mask" "F.Paste")
			(net "SW_SSD0_R")
			(options
				(clearance outline)
				(anchor circle)
			)
			(primitives
				(gr_poly
					(pts
						(arc
							(start -0.1778 0.5715)
							(mid -0.321484 0.511984)
							(end -0.381 0.3683)
						)
						(arc
							(start -0.381 -0.3683)
							(mid -0.321484 -0.511984)
							(end -0.1778 -0.5715)
						)
						(arc
							(start 0.1778 -0.5715)
							(mid 0.321484 -0.511984)
							(end 0.381 -0.3683)
						)
						(arc
							(start 0.381 0.3683)
							(mid 0.321484 0.511984)
							(end 0.1778 0.5715)
						)
					)
					(width 0)
					(fill yes)
				)
			)
		)
		(pad "G" smd custom
			(at -0.98425 0.9525 180)
			(size 0.1905 0.1905)
			(layers "F.Cu" "F.Mask" "F.Paste")
			(net "SSD0_PWREN")
			(options
				(clearance outline)
				(anchor circle)
			)
			(primitives
				(gr_poly
					(pts
						(arc
							(start -0.1778 0.5715)
							(mid -0.321484 0.511984)
							(end -0.381 0.3683)
						)
						(arc
							(start -0.381 -0.3683)
							(mid -0.321484 -0.511984)
							(end -0.1778 -0.5715)
						)
						(arc
							(start 0.1778 -0.5715)
							(mid 0.321484 -0.511984)
							(end 0.381 -0.3683)
						)
						(arc
							(start 0.381 0.3683)
							(mid 0.321484 0.511984)
							(end 0.1778 0.5715)
						)
					)
					(width 0)
					(fill yes)
				)
			)
		)
		(pad "S" smd custom
			(at 0.98425 0.9525 180)
			(size 0.1905 0.1905)
			(layers "F.Cu" "F.Mask" "F.Paste")
			(net "GND")
			(options
				(clearance outline)
				(anchor circle)
			)
			(primitives
				(gr_poly
					(pts
						(arc
							(start -0.1778 0.5715)
							(mid -0.321484 0.511984)
							(end -0.381 0.3683)
						)
						(arc
							(start -0.381 -0.3683)
							(mid -0.321484 -0.511984)
							(end -0.1778 -0.5715)
						)
						(arc
							(start 0.1778 -0.5715)
							(mid 0.321484 -0.511984)
							(end 0.381 -0.3683)
						)
						(arc
							(start 0.381 0.3683)
							(mid 0.321484 0.511984)
							(end 0.1778 0.5715)
						)
					)
					(width 0)
					(fill yes)
				)
			)
		)
	)
	(footprint ""
		(layer "F.Cu")
		(at 221.615 -268.351 180)
		(property "Reference" "PC1194"
			(at 0 0 180)
			(layer "F.SilkS")
			(hide yes)
			(effects
				(font
					(size 1.27 1.27)
				)
			)
		)
		(property "Value" "SCD1U25V3KX-GP"
			(at 0 -2.8194 180)
			(unlocked yes)
			(layer "F.Fab")
			(hide yes)
			(effects
				(font
					(size 1.016 1.016)
					(thickness 0.1524)
				)
			)
		)
		(property "Device Type" "C603H36"
			(at 0 -4.3434 180)
			(unlocked yes)
			(layer "F.Fab")
			(hide yes)
			(effects
				(font
					(size 1.016 1.016)
					(thickness 0.1524)
				)
			)
		)
		(duplicate_pad_numbers_are_jumpers no)
		(fp_line
			(start 0.508 0)
			(end -0.508 0)
			(stroke
				(width 0.2032)
				(type default)
			)
			(layer "F.SilkS")
		)
		(fp_rect
			(start -0.5842 1.3335)
			(end 0.5842 -1.3335)
			(stroke
				(width 0)
				(type default)
			)
			(fill no)
			(layer "F.CrtYd")
		)
		(fp_rect
			(start -0.5842 1.3335)
			(end 0.5842 -1.3335)
			(stroke
				(width 0)
				(type default)
			)
			(fill no)
			(layer "F.Fab")
		)
		(pad "1" smd custom
			(at 0 -0.762 180)
			(size 0.2159 0.2159)
			(layers "F.Cu" "F.Mask" "F.Paste")
			(net "P3V3")
			(options
				(clearance outline)
				(anchor circle)
			)
			(primitives
				(gr_poly
					(pts
						(arc
							(start -0.3302 -0.4318)
							(mid -0.402042 -0.402042)
							(end -0.4318 -0.3302)
						)
						(arc
							(start -0.4318 0.3302)
							(mid -0.402042 0.402042)
							(end -0.3302 0.4318)
						)
						(arc
							(start 0.3302 0.4318)
							(mid 0.402042 0.402042)
							(end 0.4318 0.3302)
						)
						(arc
							(start 0.4318 -0.3302)
							(mid 0.402042 -0.402042)
							(end 0.3302 -0.4318)
						)
					)
					(width 0)
					(fill yes)
				)
			)
		)
		(pad "2" smd custom
			(at 0 0.762 180)
			(size 0.2159 0.2159)
			(layers "F.Cu" "F.Mask" "F.Paste")
			(net "GND")
			(options
				(clearance outline)
				(anchor circle)
			)
			(primitives
				(gr_poly
					(pts
						(arc
							(start -0.3302 -0.4318)
							(mid -0.402042 -0.402042)
							(end -0.4318 -0.3302)
						)
						(arc
							(start -0.4318 0.3302)
							(mid -0.402042 0.402042)
							(end -0.3302 0.4318)
						)
						(arc
							(start 0.3302 0.4318)
							(mid 0.402042 0.402042)
							(end 0.4318 0.3302)
						)
						(arc
							(start 0.4318 -0.3302)
							(mid 0.402042 -0.402042)
							(end 0.3302 -0.4318)
						)
					)
					(width 0)
					(fill yes)
				)
			)
		)
	)
	(footprint ""
		(layer "F.Cu")
		(at 42.92473 -142.345664 90)
		(property "Reference" "R9944"
			(at 0 0 90)
			(layer "F.SilkS")
			(hide yes)
			(effects
				(font
					(size 1.27 1.27)
				)
			)
		)
		(property "Value" "4K7R2J-2-GP"
			(at 0.064008 -3.993896 90)
			(unlocked yes)
			(layer "F.Fab")
			(hide yes)
			(effects
				(font
					(size 1.016 1.016)
					(thickness 0.1524)
				)
			)
		)
		(property "Device Type" "R402H16"
			(at 0.064008 -5.517896 90)
			(unlocked yes)
			(layer "F.Fab")
			(hide yes)
			(effects
				(font
					(size 1.016 1.016)
					(thickness 0.1524)
				)
			)
		)
		(duplicate_pad_numbers_are_jumpers no)
		(fp_line
			(start 0.508 -0.9398)
			(end -0.508 -0.9398)
			(stroke
				(width 0.1524)
				(type default)
			)
			(layer "F.SilkS")
		)
		(fp_line
			(start -0.508 -0.9398)
			(end -0.508 0.9398)
			(stroke
				(width 0.1524)
				(type default)
			)
			(layer "F.SilkS")
		)
		(fp_rect
			(start -0.508 0.9398)
			(end 0.508 -0.9398)
			(stroke
				(width 0)
				(type default)
			)
			(fill no)
			(layer "F.CrtYd")
		)
		(fp_rect
			(start -0.508 0.9398)
			(end 0.508 -0.9398)
			(stroke
				(width 0)
				(type default)
			)
			(fill no)
			(layer "F.Fab")
		)
		(pad "1" smd custom
			(at 0 -0.4445 90)
			(size 0.1397 0.1397)
			(layers "F.Cu" "F.Mask" "F.Paste")
			(net "P3V3")
			(options
				(clearance outline)
				(anchor circle)
			)
			(primitives
				(gr_poly
					(pts
						(arc
							(start -0.1778 -0.2794)
							(mid -0.249642 -0.249642)
							(end -0.2794 -0.1778)
						)
						(arc
							(start -0.2794 0.1778)
							(mid -0.249642 0.249642)
							(end -0.1778 0.2794)
						)
						(arc
							(start 0.1778 0.2794)
							(mid 0.249642 0.249642)
							(end 0.2794 0.1778)
						)
						(arc
							(start 0.2794 -0.1778)
							(mid 0.249642 -0.249642)
							(end 0.1778 -0.2794)
						)
					)
					(width 0)
					(fill yes)
				)
			)
		)
		(pad "2" smd custom
			(at 0 0.4445 90)
			(size 0.1397 0.1397)
			(layers "F.Cu" "F.Mask" "F.Paste")
			(net "SSD_ACT_DR8_MOS_N")
			(options
				(clearance outline)
				(anchor circle)
			)
			(primitives
				(gr_poly
					(pts
						(arc
							(start -0.1778 -0.2794)
							(mid -0.249642 -0.249642)
							(end -0.2794 -0.1778)
						)
						(arc
							(start -0.2794 0.1778)
							(mid -0.249642 0.249642)
							(end -0.1778 0.2794)
						)
						(arc
							(start 0.1778 0.2794)
							(mid 0.249642 0.249642)
							(end 0.2794 0.1778)
						)
						(arc
							(start 0.2794 -0.1778)
							(mid 0.249642 -0.249642)
							(end 0.1778 -0.2794)
						)
					)
					(width 0)
					(fill yes)
				)
			)
		)
	)
	(footprint ""
		(layer "F.Cu")
		(at 97.028 -293.116 90)
		(property "Reference" "C939"
			(at 0 0 90)
			(layer "F.SilkS")
			(hide yes)
			(effects
				(font
					(size 1.27 1.27)
				)
			)
		)
		(property "Value" "SC1KP50V2KX-1GP"
			(at 1.1811 -2.7051 90)
			(unlocked yes)
			(layer "F.Fab")
			(hide yes)
			(effects
				(font
					(size 1.016 1.016)
					(thickness 0.1524)
				)
			)
		)
		(property "Device Type" "C402H22"
			(at 1.1811 -4.2291 90)
			(unlocked yes)
			(layer "F.Fab")
			(hide yes)
			(effects
				(font
					(size 1.016 1.016)
					(thickness 0.1524)
				)
			)
		)
		(duplicate_pad_numbers_are_jumpers no)
		(fp_rect
			(start -0.4318 0.9525)
			(end 0.4318 -0.9525)
			(stroke
				(width 0)
				(type default)
			)
			(fill no)
			(layer "F.CrtYd")
		)
		(fp_rect
			(start -0.4318 0.9525)
			(end 0.4318 -0.9525)
			(stroke
				(width 0)
				(type default)
			)
			(fill no)
			(layer "F.Fab")
		)
		(pad "1" smd custom
			(at 0 -0.4445 90)
			(size 0.1524 0.1524)
			(layers "F.Cu" "F.Mask" "F.Paste")
			(net "SSD_PRSNT2")
			(options
				(clearance outline)
				(anchor circle)
			)
			(primitives
				(gr_poly
					(pts
						(arc
							(start 0.3048 -0.2032)
							(mid 0.275042 -0.275042)
							(end 0.2032 -0.3048)
						)
						(arc
							(start -0.2032 -0.3048)
							(mid -0.275042 -0.275042)
							(end -0.3048 -0.2032)
						)
						(arc
							(start -0.3048 0.2032)
							(mid -0.275042 0.275042)
							(end -0.2032 0.3048)
						)
						(arc
							(start 0.2032 0.3048)
							(mid 0.275042 0.275042)
							(end 0.3048 0.2032)
						)
					)
					(width 0)
					(fill yes)
				)
			)
		)
		(pad "2" smd custom
			(at 0 0.4445 90)
			(size 0.1524 0.1524)
			(layers "F.Cu" "F.Mask" "F.Paste")
			(net "GND")
			(options
				(clearance outline)
				(anchor circle)
			)
			(primitives
				(gr_poly
					(pts
						(arc
							(start 0.3048 -0.2032)
							(mid 0.275042 -0.275042)
							(end 0.2032 -0.3048)
						)
						(arc
							(start -0.2032 -0.3048)
							(mid -0.275042 -0.275042)
							(end -0.3048 -0.2032)
						)
						(arc
							(start -0.3048 0.2032)
							(mid -0.275042 0.275042)
							(end -0.2032 0.3048)
						)
						(arc
							(start 0.2032 0.3048)
							(mid 0.275042 0.275042)
							(end 0.3048 0.2032)
						)
					)
					(width 0)
					(fill yes)
				)
			)
		)
	)
)
